(kicad_pcb
	(version 20260206)
	(generator "pcbnew")
	(generator_version "10.0")
	(general
		(thickness 1.6)
		(legacy_teardrops no)
	)
	(paper "A4")
	(title_block
		(title "v1-chassis-manager — T6M_CM_d_v01_1031_1645.brd")
		(comment 1 "Open CloudServer (Microsoft) / footprints 1218-1223 of 2512")
	)
	(layers
		(0 "F.Cu" signal "TOP")
		(4 "In1.Cu" signal "GND1")
		(6 "In2.Cu" signal "IN1")
		(8 "In3.Cu" signal "VCC1")
		(10 "In4.Cu" signal "VCC2")
		(12 "In5.Cu" signal "GND2")
		(14 "In6.Cu" signal "IN2")
		(16 "In7.Cu" signal "IN3")
		(18 "In8.Cu" signal "GND3")
		(2 "B.Cu" signal "BOTTOM")
		(9 "F.Adhes" user "F.Adhesive")
		(11 "B.Adhes" user "B.Adhesive")
		(13 "F.Paste" user "Package Geometry/Pastemask Top")
		(15 "B.Paste" user "Package Geometry/Pastemask Bottom")
		(5 "F.SilkS" user "Ref Des/Silkscreen Top")
		(7 "B.SilkS" user "Ref Des/Silkscreen Bottom")
		(1 "F.Mask" user "Board Geometry/Soldermask Top")
		(3 "B.Mask" user "Board Geometry/Soldermask Bottom")
		(17 "Dwgs.User" user "User.Drawings")
		(19 "Cmts.User" user "User.Comments")
		(21 "Eco1.User" user "User.Eco1")
		(23 "Eco2.User" user "User.Eco2")
		(25 "Edge.Cuts" user "Board Geometry/Outline")
		(27 "Margin" user)
		(31 "F.CrtYd" user "Package Geometry/Place Bound Top")
		(29 "B.CrtYd" user "Package Geometry/Place Bound Bottom")
		(35 "F.Fab" user "Ref Des/Assembly Top")
		(33 "B.Fab" user "Ref Des/Assembly Bottom")
	)
	(footprint ""
		(layer "F.Cu")
		(at 185.2676 -188.4172 -90)
		(property "Reference" "R1072"
			(at -1.1176 -0.28067 90)
			(unlocked yes)
			(layer "F.SilkS")
			(effects
				(font
					(size 0.7874 0.5842)
					(thickness 0.1524)
				)
				(justify left)
			)
		)
		(property "Value" ""
			(at 0 0 270)
			(layer "F.Fab")
			(effects
				(font
					(size 1.27 1.27)
				)
			)
		)
		(duplicate_pad_numbers_are_jumpers no)
		(fp_line
			(start -0.7874 0.4064)
			(end -0.7874 -0.4064)
			(stroke
				(width 0.1524)
				(type default)
			)
			(layer "F.SilkS")
		)
		(fp_line
			(start 0.7874 0.4064)
			(end -0.7874 0.4064)
			(stroke
				(width 0.1524)
				(type default)
			)
			(layer "F.SilkS")
		)
		(fp_line
			(start -0.7874 -0.4064)
			(end 0.7874 -0.4064)
			(stroke
				(width 0.1524)
				(type default)
			)
			(layer "F.SilkS")
		)
		(fp_line
			(start 0.7874 -0.4064)
			(end 0.7874 0.4064)
			(stroke
				(width 0.1524)
				(type default)
			)
			(layer "F.SilkS")
		)
		(fp_poly
			(pts
				(xy -0.508 0.2794) (xy -0.508 0.2286) (xy -0.635 0.2286) (xy -0.635 -0.254) (xy -0.5334 -0.254)
				(xy -0.5334 -0.2794) (xy 0.5334 -0.2794) (xy 0.5334 -0.254) (xy 0.635 -0.254) (xy 0.635 0.254) (xy 0.5334 0.254)
				(xy 0.5334 0.2794)
			)
			(stroke
				(width 0)
				(type default)
			)
			(fill no)
			(layer "F.CrtYd")
		)
		(pad "1" smd rect
			(at 0.40005 0 270)
			(size 0.4572 0.508)
			(layers "F.Cu" "F.Mask" "F.Paste")
			(net "POWER_SW1_PWR_CTR_12V")
		)
		(pad "2" smd rect
			(at -0.40005 0 270)
			(size 0.4572 0.508)
			(layers "F.Cu" "F.Mask" "F.Paste")
			(net "POWER_SW1_PWR_CTR_12V_R")
		)
	)
	(footprint ""
		(layer "F.Cu")
		(at 28.466288 -123.274582 90)
		(property "Reference" "C829"
			(at -4.108958 -1.249934 90)
			(unlocked yes)
			(layer "F.SilkS")
			(effects
				(font
					(size 0.7874 0.5842)
					(thickness 0.1524)
				)
				(justify left)
			)
		)
		(property "Value" ""
			(at 0 0 90)
			(layer "F.Fab")
			(effects
				(font
					(size 1.27 1.27)
				)
			)
		)
		(duplicate_pad_numbers_are_jumpers no)
		(fp_line
			(start 0.7874 -0.4064)
			(end 0.7874 0.4064)
			(stroke
				(width 0.1524)
				(type default)
			)
			(layer "F.SilkS")
		)
		(fp_line
			(start -0.7874 -0.4064)
			(end 0.7874 -0.4064)
			(stroke
				(width 0.1524)
				(type default)
			)
			(layer "F.SilkS")
		)
		(fp_line
			(start 0 0.381)
			(end 0 -0.381)
			(stroke
				(width 0.1524)
				(type default)
			)
			(layer "F.SilkS")
		)
		(fp_line
			(start 0.7874 0.4064)
			(end -0.7874 0.4064)
			(stroke
				(width 0.1524)
				(type default)
			)
			(layer "F.SilkS")
		)
		(fp_line
			(start -0.7874 0.4064)
			(end -0.7874 -0.4064)
			(stroke
				(width 0.1524)
				(type default)
			)
			(layer "F.SilkS")
		)
		(fp_poly
			(pts
				(xy -0.5334 0.254) (xy -0.635 0.254) (xy -0.635 0.2286) (xy -0.635 -0.254) (xy -0.5334 -0.254) (xy -0.5334 -0.2794)
				(xy 0.5334 -0.2794) (xy 0.5334 -0.254) (xy 0.635 -0.254) (xy 0.635 0.254) (xy 0.5334 0.254) (xy 0.5334 0.2794)
				(xy -0.508 0.2794) (xy -0.5334 0.2794)
			)
			(stroke
				(width 0)
				(type default)
			)
			(fill no)
			(layer "F.CrtYd")
		)
		(pad "1" smd rect
			(at 0.40005 0 90)
			(size 0.4572 0.508)
			(layers "F.Cu" "F.Mask" "F.Paste")
			(net "FM_CPLD_NODE1_P1V538_BMC_EN")
		)
		(pad "2" smd rect
			(at -0.40005 0 90)
			(size 0.4572 0.508)
			(layers "F.Cu" "F.Mask" "F.Paste")
			(net "GND")
		)
	)
	(footprint ""
		(layer "F.Cu")
		(at 168.87698 -169.633646 -90)
		(property "Reference" "C563"
			(at -0.430784 -2.786126 0)
			(unlocked yes)
			(layer "F.SilkS")
			(effects
				(font
					(size 0.7874 0.5842)
					(thickness 0.1524)
				)
				(justify left)
			)
		)
		(property "Value" ""
			(at 0 0 270)
			(layer "F.Fab")
			(effects
				(font
					(size 1.27 1.27)
				)
			)
		)
		(duplicate_pad_numbers_are_jumpers no)
		(fp_line
			(start -0.7874 0.4064)
			(end -0.7874 -0.4064)
			(stroke
				(width 0.1524)
				(type default)
			)
			(layer "F.SilkS")
		)
		(fp_line
			(start 0.7874 0.4064)
			(end -0.7874 0.4064)
			(stroke
				(width 0.1524)
				(type default)
			)
			(layer "F.SilkS")
		)
		(fp_line
			(start 0 0.381)
			(end 0 -0.381)
			(stroke
				(width 0.1524)
				(type default)
			)
			(layer "F.SilkS")
		)
		(fp_line
			(start -0.7874 -0.4064)
			(end 0.7874 -0.4064)
			(stroke
				(width 0.1524)
				(type default)
			)
			(layer "F.SilkS")
		)
		(fp_line
			(start 0.7874 -0.4064)
			(end 0.7874 0.4064)
			(stroke
				(width 0.1524)
				(type default)
			)
			(layer "F.SilkS")
		)
		(fp_poly
			(pts
				(xy -0.5334 0.254) (xy -0.635 0.254) (xy -0.635 0.2286) (xy -0.635 -0.254) (xy -0.5334 -0.254) (xy -0.5334 -0.2794)
				(xy 0.5334 -0.2794) (xy 0.5334 -0.254) (xy 0.635 -0.254) (xy 0.635 0.254) (xy 0.5334 0.254) (xy 0.5334 0.2794)
				(xy -0.508 0.2794) (xy -0.5334 0.2794)
			)
			(stroke
				(width 0)
				(type default)
			)
			(fill no)
			(layer "F.CrtYd")
		)
		(pad "1" smd rect
			(at 0.40005 0 270)
			(size 0.4572 0.508)
			(layers "F.Cu" "F.Mask" "F.Paste")
			(net "N54365611")
		)
		(pad "2" smd rect
			(at -0.40005 0 270)
			(size 0.4572 0.508)
			(layers "F.Cu" "F.Mask" "F.Paste")
			(net "N54365613")
		)
	)
	(footprint ""
		(layer "F.Cu")
		(at 187.7695 -164.040566)
		(property "Reference" "R1278"
			(at -1.672844 5.349494 0)
			(unlocked yes)
			(layer "F.SilkS")
			(effects
				(font
					(size 0.7874 0.5842)
					(thickness 0.1524)
				)
				(justify left)
			)
		)
		(property "Value" ""
			(at 0 0 0)
			(layer "F.Fab")
			(effects
				(font
					(size 1.27 1.27)
				)
			)
		)
		(duplicate_pad_numbers_are_jumpers no)
		(fp_line
			(start -0.7874 -0.4064)
			(end 0.7874 -0.4064)
			(stroke
				(width 0.1524)
				(type default)
			)
			(layer "F.SilkS")
		)
		(fp_line
			(start -0.7874 0.4064)
			(end -0.7874 -0.4064)
			(stroke
				(width 0.1524)
				(type default)
			)
			(layer "F.SilkS")
		)
		(fp_line
			(start 0.7874 -0.4064)
			(end 0.7874 0.4064)
			(stroke
				(width 0.1524)
				(type default)
			)
			(layer "F.SilkS")
		)
		(fp_line
			(start 0.7874 0.4064)
			(end -0.7874 0.4064)
			(stroke
				(width 0.1524)
				(type default)
			)
			(layer "F.SilkS")
		)
		(fp_poly
			(pts
				(xy -0.508 0.2794) (xy -0.508 0.2286) (xy -0.635 0.2286) (xy -0.635 -0.254) (xy -0.5334 -0.254)
				(xy -0.5334 -0.2794) (xy 0.5334 -0.2794) (xy 0.5334 -0.254) (xy 0.635 -0.254) (xy 0.635 0.254) (xy 0.5334 0.254)
				(xy 0.5334 0.2794)
			)
			(stroke
				(width 0)
				(type default)
			)
			(fill no)
			(layer "F.CrtYd")
		)
		(pad "1" smd rect
			(at 0.40005 0)
			(size 0.4572 0.508)
			(layers "F.Cu" "F.Mask" "F.Paste")
			(net "N54134271")
		)
		(pad "2" smd rect
			(at -0.40005 0)
			(size 0.4572 0.508)
			(layers "F.Cu" "F.Mask" "F.Paste")
			(net "LAN2_P2_R")
		)
	)
	(footprint ""
		(layer "F.Cu")
		(at 177.40122 -53.881528 90)
		(property "Reference" "D10"
			(at 2.388616 -4.25323 0)
			(unlocked yes)
			(layer "F.SilkS")
			(effects
				(font
					(size 0.7874 0.5842)
					(thickness 0.1524)
				)
				(justify left)
			)
		)
		(property "Value" ""
			(at 0 0 90)
			(layer "F.Fab")
			(effects
				(font
					(size 1.27 1.27)
				)
			)
		)
		(duplicate_pad_numbers_are_jumpers no)
		(fp_line
			(start 0.450088 -1.370076)
			(end -0.450088 -1.370076)
			(stroke
				(width 0.1524)
				(type default)
			)
			(layer "F.SilkS")
		)
		(fp_line
			(start -0.450088 -1.370076)
			(end -0.450088 0.430022)
			(stroke
				(width 0.1524)
				(type default)
			)
			(layer "F.SilkS")
		)
		(fp_line
			(start -0.2794 -1.2954)
			(end 0.4064 -1.27)
			(stroke
				(width 0.1524)
				(type default)
			)
			(layer "F.SilkS")
		)
		(fp_line
			(start 0.4064 -1.27)
			(end -0.381 -1.27)
			(stroke
				(width 0.1524)
				(type default)
			)
			(layer "F.SilkS")
		)
		(fp_line
			(start -0.149098 -0.487172)
			(end 0.185674 -0.487172)
			(stroke
				(width 0.050038)
				(type default)
			)
			(layer "F.SilkS")
		)
		(fp_line
			(start 0.0127 -0.4699)
			(end -0.0762 -0.3556)
			(stroke
				(width 0.050038)
				(type default)
			)
			(layer "F.SilkS")
		)
		(fp_line
			(start 0.1016 -0.3556)
			(end 0.0127 -0.4699)
			(stroke
				(width 0.050038)
				(type default)
			)
			(layer "F.SilkS")
		)
		(fp_line
			(start -0.0762 -0.3556)
			(end 0.1016 -0.3556)
			(stroke
				(width 0.050038)
				(type default)
			)
			(layer "F.SilkS")
		)
		(fp_line
			(start 0.450088 0.430022)
			(end 0.450088 -1.35001)
			(stroke
				(width 0.1524)
				(type default)
			)
			(layer "F.SilkS")
		)
		(fp_line
			(start -0.450088 0.430022)
			(end 0.450088 0.430022)
			(stroke
				(width 0.1524)
				(type default)
			)
			(layer "F.SilkS")
		)
		(fp_poly
			(pts
				(xy -0.350012 -0.501142) (xy -0.350012 -0.348742) (xy -0.3556 -0.348742) (xy -0.3556 0.337058) (xy 0.3556 0.337058)
				(xy 0.3556 -0.348742) (xy 0.350012 -0.348742) (xy 0.350012 -0.475742) (xy 0.3556 -0.475742) (xy 0.3556 -1.186942)
				(xy -0.3556 -1.186942) (xy -0.3556 -0.501142)
			)
			(stroke
				(width 0)
				(type default)
			)
			(fill no)
			(layer "F.CrtYd")
		)
		(fp_line
			(start 0.350012 -0.975106)
			(end -0.350012 -0.975106)
			(stroke
				(width 0.1)
				(type default)
			)
			(layer "F.Fab")
		)
		(fp_line
			(start -0.350012 -0.975106)
			(end -0.350012 0.124968)
			(stroke
				(width 0.1)
				(type default)
			)
			(layer "F.Fab")
		)
		(fp_line
			(start 0.350012 0.124968)
			(end 0.350012 -0.975106)
			(stroke
				(width 0.1)
				(type default)
			)
			(layer "F.Fab")
		)
		(fp_line
			(start -0.350012 0.124968)
			(end 0.350012 0.124968)
			(stroke
				(width 0.1)
				(type default)
			)
			(layer "F.Fab")
		)
		(fp_text user "-"
			(at -0.734568 -1.92024 0)
			(unlocked yes)
			(layer "F.SilkS")
			(effects
				(font
					(size 1.27 0.9652)
					(thickness 0.1524)
				)
				(justify left)
			)
		)
		(fp_text user "+"
			(at 0.494538 1.40081 180)
			(unlocked yes)
			(layer "F.SilkS")
			(effects
				(font
					(size 1.27 0.9652)
					(thickness 0.1524)
				)
				(justify left)
			)
		)
		(pad "A" smd rect
			(at 0 0 180)
			(size 0.5588 0.6096)
			(layers "F.Cu" "F.Mask" "F.Paste")
			(net "GND")
		)
		(pad "C" smd rect
			(at 0 -0.849884)
			(size 0.5588 0.6096)
			(layers "F.Cu" "F.Mask" "F.Paste")
			(net "USBPWR_P1")
		)
	)
	(footprint ""
		(layer "F.Cu")
		(at 16.278606 -126.354078)
		(property "Reference" "PQ1"
			(at 7.107936 2.467356 90)
			(unlocked yes)
			(layer "F.SilkS")
			(effects
				(font
					(size 0.7874 0.5842)
					(thickness 0.1524)
				)
				(justify left)
			)
		)
		(property "Value" ""
			(at 0 0 0)
			(layer "F.Fab")
			(effects
				(font
					(size 1.27 1.27)
				)
			)
		)
		(duplicate_pad_numbers_are_jumpers no)
		(fp_line
			(start -0.157988 -0.525018)
			(end 4.341876 -0.525018)
			(stroke
				(width 0.1524)
				(type default)
			)
			(layer "F.SilkS")
		)
		(fp_line
			(start -0.157988 -0.294894)
			(end -0.157988 -0.525018)
			(stroke
				(width 0.1524)
				(type default)
			)
			(layer "F.SilkS")
		)
		(fp_line
			(start -0.157988 2.47523)
			(end -0.157988 2.245106)
			(stroke
				(width 0.1524)
				(type default)
			)
			(layer "F.SilkS")
		)
		(fp_line
			(start 4.341876 -0.525018)
			(end 4.341876 -0.294894)
			(stroke
				(width 0.1524)
				(type default)
			)
			(layer "F.SilkS")
		)
		(fp_line
			(start 4.341876 2.245106)
			(end 4.341876 2.47523)
			(stroke
				(width 0.1524)
				(type default)
			)
			(layer "F.SilkS")
		)
		(fp_line
			(start 4.341876 2.47523)
			(end -0.157988 2.47523)
			(stroke
				(width 0.1524)
				(type default)
			)
			(layer "F.SilkS")
		)
		(fp_poly
			(pts
				(xy -0.615188 -0.030988) (xy -1.69291 0.328168) (xy -0.974344 1.046734)
			)
			(stroke
				(width 0)
				(type default)
			)
			(fill yes)
			(layer "F.SilkS")
		)
		(fp_poly
			(pts
				(xy -0.157988 -0.525018) (xy -0.157988 -0.294894) (xy -0.346456 -0.294894) (xy -0.346456 2.245106)
				(xy -0.157988 2.245106) (xy -0.157988 2.47523) (xy 4.341876 2.47523) (xy 4.341876 2.245106) (xy 4.530344 2.245106)
				(xy 4.530344 -0.294894) (xy 4.341876 -0.294894) (xy 4.341876 -0.525018)
			)
			(stroke
				(width 0)
				(type default)
			)
			(fill no)
			(layer "F.CrtYd")
		)
		(fp_line
			(start -0.157988 -0.525018)
			(end 4.341876 -0.525018)
			(stroke
				(width 0.1)
				(type default)
			)
			(layer "F.Fab")
		)
		(fp_line
			(start -0.157988 2.47523)
			(end -0.157988 -0.525018)
			(stroke
				(width 0.1)
				(type default)
			)
			(layer "F.Fab")
		)
		(fp_line
			(start 4.341876 -0.525018)
			(end 4.341876 2.47523)
			(stroke
				(width 0.1)
				(type default)
			)
			(layer "F.Fab")
		)
		(fp_line
			(start 4.341876 2.47523)
			(end -0.157988 2.47523)
			(stroke
				(width 0.1)
				(type default)
			)
			(layer "F.Fab")
		)
		(fp_circle
			(center 2.091944 0.975106)
			(end 2.221484 0.975106)
			(stroke
				(width 0.1)
				(type default)
			)
			(fill no)
			(layer "F.Fab")
		)
		(fp_poly
			(pts
				(xy -0.339598 0) (xy -1.355598 -0.508) (xy -1.355598 0.508)
			)
			(stroke
				(width 0)
				(type default)
			)
			(fill yes)
			(layer "F.Fab")
		)
		(pad "1" smd rect
			(at 0 0 270)
			(size 0.4318 0.5588)
			(layers "F.Cu" "F.Mask" "F.Paste")
			(net "SW_P1V05_NODE1_DRVH")
		)
		(pad "2" smd rect
			(at 0 0.649986 270)
			(size 0.4318 0.5588)
			(layers "F.Cu" "F.Mask" "F.Paste")
			(net "SW_P1V05_NODE1_VIN_FLT")
		)
		(pad "3" smd rect
			(at 0 1.300226 270)
			(size 0.4318 0.5588)
			(layers "F.Cu" "F.Mask" "F.Paste")
			(net "SW_P1V05_NODE1_VIN_FLT")
		)
		(pad "4" smd rect
			(at 0 1.950212 270)
			(size 0.4318 0.5588)
			(layers "F.Cu" "F.Mask" "F.Paste")
			(net "SW_P1V05_NODE1_VIN_FLT")
		)
		(pad "5-6-7" smd custom
			(at 4.181856 1.300226 270)
			(size 0.143764 0.143764)
			(layers "F.Cu" "F.Mask" "F.Paste")
			(net "GND")
			(options
				(clearance outline)
				(anchor circle)
			)
			(primitives
				(gr_poly
					(pts
						(xy -0.87503 -0.287528) (xy -0.87503 0.287528) (xy 0.87503 0.287528) (xy 0.87503 -0.287528) (xy 0.424942 -0.287528)
						(xy 0.424942 -0.180086) (xy 0.424942 -0.107442) (xy 0.225044 -0.107442) (xy 0.225044 -0.180086)
						(xy 0.225044 -0.287528) (xy -0.225044 -0.287528) (xy -0.225044 -0.180086) (xy -0.225044 -0.107442)
						(xy -0.424942 -0.107442) (xy -0.424942 -0.180086) (xy -0.424942 -0.287528) (xy -0.42545 -0.287528)
					)
					(width 0)
					(fill yes)
				)
			)
		)
		(pad "8" smd rect
			(at 4.181856 0 270)
			(size 0.4318 0.5588)
			(layers "F.Cu" "F.Mask" "F.Paste")
			(net "SW_P1V05_NODE1_DRVL")
		)
		(pad "D1_EP" smd rect
			(at 0.901954 0.975106)
			(size 0.8382 2.5146)
			(layers "F.Cu" "F.Mask" "F.Paste")
			(net "SW_P1V05_NODE1_VIN_FLT")
		)
		(pad "S1/D2_EP" smd rect
			(at 2.675128 0.975106)
			(size 2.032 2.5146)
			(layers "F.Cu" "F.Mask" "F.Paste")
			(net "SW_P1V05_NODE1_PH")
		)
		(zone
			(layer "F.Cu")
			(hatch none 0.5)
			(connect_pads
				(clearance 0)
			)
			(min_thickness 0.25)
			(keepout
				(tracks allowed)
				(vias not_allowed)
				(pads allowed)
				(copperpour not_allowed)
				(footprints allowed)
			)
			(placement
				(enabled no)
				(sheetname "")
			)
			(fill
				(thermal_gap 0.5)
				(thermal_bridge_width 0.5)
				(island_removal_mode 0)
			)
			(polygon
				(pts
					(xy 16.634206 -123.890278) (xy 16.634206 -126.862078) (xy 20.114006 -126.862078) (xy 20.114006 -123.890278)
					(xy 16.735806 -123.890278) (xy 16.710406 -123.890278) (xy 16.710406 -124.042678) (xy 16.735806 -124.042678)
					(xy 17.675606 -124.042678) (xy 17.675606 -126.684278) (xy 17.878806 -126.684278) (xy 17.878806 -124.068078)
					(xy 20.037806 -124.068078) (xy 20.037806 -126.709678) (xy 16.685006 -126.709678) (xy 16.685006 -123.890278)
				)
			)
		)
	)
)
